# T6G (Grand Teton) — schematic netlist excerpt (pin names and nets, part order shuffled) for the footprints in the layout excerpt that follows; sources: Cadence DE-HDL packaged netlist, KiCad conversion of 04192023_DAF0TMB3IC0_F0TG_MB_C_brd_V02_OCP.brd

R3500  Q_RES  4.7K 5% CHIP  pkg 0402LF  page 247 : A = P3V3_OCP_SFF ; B = SMB_OCP_SFF_3V3AUX_BUF_SCL

(kicad_pcb
	(version 20260206)
	(generator "pcbnew")
	(generator_version "10.0")
	(general
		(thickness 1.6)
		(legacy_teardrops no)
	)
	(paper "A4")
	(title_block
		(title "04192023_DAF0TMB3IC0_F0TG_MB_C_brd_V02_OCP.brd")
		(comment 1 "Grand Teton / footprints 483-483 of 8354")
	)
	(layers
		(0 "F.Cu" signal "TOP")
		(4 "In1.Cu" signal "GND")
		(6 "In2.Cu" signal "IN1")
		(8 "In3.Cu" signal "GND1")
		(10 "In4.Cu" signal "IN2")
		(12 "In5.Cu" signal "GND2")
		(14 "In6.Cu" signal "IN3")
		(16 "In7.Cu" signal "GND3")
		(18 "In8.Cu" signal "VCC")
		(20 "In9.Cu" signal "VCC1")
		(22 "In10.Cu" signal "GND4")
		(24 "In11.Cu" signal "IN4")
		(26 "In12.Cu" signal "GND5")
		(28 "In13.Cu" signal "IN5")
		(30 "In14.Cu" signal "GND6")
		(32 "In15.Cu" signal "IN6")
		(34 "In16.Cu" signal "GND7")
		(2 "B.Cu" signal "BOTTOM")
		(9 "F.Adhes" user "F.Adhesive")
		(11 "B.Adhes" user "B.Adhesive")
		(13 "F.Paste" user "Package Geometry/Pastemask Top")
		(15 "B.Paste" user "Package Geometry/Pastemask Bottom")
		(5 "F.SilkS" user "Ref Des/Silkscreen Top")
		(7 "B.SilkS" user "Ref Des/Silkscreen Bottom")
		(1 "F.Mask" user "Board Geometry/Soldermask Top")
		(3 "B.Mask" user "Board Geometry/Soldermask Bottom")
		(17 "Dwgs.User" user "User.Drawings")
		(19 "Cmts.User" user "User.Comments")
		(21 "Eco1.User" user "User.Eco1")
		(23 "Eco2.User" user "User.Eco2")
		(25 "Edge.Cuts" user "Board Geometry/Outline")
		(27 "Margin" user)
		(31 "F.CrtYd" user "Package Geometry/Place Bound Top")
		(29 "B.CrtYd" user "Package Geometry/Place Bound Bottom")
		(35 "F.Fab" user "Ref Des/Assembly Top")
		(33 "B.Fab" user "Ref Des/Assembly Bottom")
	)
	(footprint ""
		(layer "F.Cu")
		(at 412.472886 -75.880468 180)
		(property "Reference" "R3500"
			(at 0 0 180)
			(layer "F.SilkS")
			(hide yes)
			(effects
				(font
					(size 1.27 1.27)
				)
			)
		)
		(property "Value" ""
			(at 0 0 180)
			(layer "F.Fab")
			(effects
				(font
					(size 1.27 1.27)
				)
			)
		)
		(duplicate_pad_numbers_are_jumpers no)
		(fp_line
			(start 0.7874 0.4064)
			(end -0.7874 0.4064)
			(stroke
				(width 0.1524)
				(type default)
			)
			(layer "F.SilkS")
		)
		(fp_line
			(start 0.7874 -0.4064)
			(end 0.7874 0.4064)
			(stroke
				(width 0.1524)
				(type default)
			)
			(layer "F.SilkS")
		)
		(fp_line
			(start -0.7874 0.4064)
			(end -0.7874 -0.4064)
			(stroke
				(width 0.1524)
				(type default)
			)
			(layer "F.SilkS")
		)
		(fp_line
			(start -0.7874 -0.4064)
			(end 0.7874 -0.4064)
			(stroke
				(width 0.1524)
				(type default)
			)
			(layer "F.SilkS")
		)
		(fp_line
			(start 0.67945 0.3048)
			(end 0.120396 0.3048)
			(stroke
				(width 0.1)
				(type default)
			)
			(layer "F.Fab")
		)
		(fp_line
			(start 0.67945 -0.3048)
			(end 0.67945 0.3048)
			(stroke
				(width 0.1)
				(type default)
			)
			(layer "F.Fab")
		)
		(fp_line
			(start 0.12065 -0.2794)
			(end 0.12065 -0.3048)
			(stroke
				(width 0.1)
				(type default)
			)
			(layer "F.Fab")
		)
		(fp_line
			(start 0.12065 -0.3048)
			(end 0.67945 -0.3048)
			(stroke
				(width 0.1)
				(type default)
			)
			(layer "F.Fab")
		)
		(fp_line
			(start 0.120396 0.3048)
			(end 0.120396 0.2794)
			(stroke
				(width 0.1)
				(type default)
			)
			(layer "F.Fab")
		)
		(fp_line
			(start 0.120396 0.2794)
			(end -0.12065 0.2794)
			(stroke
				(width 0.1)
				(type default)
			)
			(layer "F.Fab")
		)
		(fp_line
			(start -0.12065 0.3048)
			(end -0.67945 0.3048)
			(stroke
				(width 0.1)
				(type default)
			)
			(layer "F.Fab")
		)
		(fp_line
			(start -0.12065 0.2794)
			(end -0.12065 0.3048)
			(stroke
				(width 0.1)
				(type default)
			)
			(layer "F.Fab")
		)
		(fp_line
			(start -0.12065 -0.2794)
			(end 0.12065 -0.2794)
			(stroke
				(width 0.1)
				(type default)
			)
			(layer "F.Fab")
		)
		(fp_line
			(start -0.12065 -0.305054)
			(end -0.12065 -0.2794)
			(stroke
				(width 0.1)
				(type default)
			)
			(layer "F.Fab")
		)
		(fp_line
			(start -0.67945 0.3048)
			(end -0.67945 -0.305054)
			(stroke
				(width 0.1)
				(type default)
			)
			(layer "F.Fab")
		)
		(fp_line
			(start -0.67945 -0.305054)
			(end -0.12065 -0.305054)
			(stroke
				(width 0.1)
				(type default)
			)
			(layer "F.Fab")
		)
		(pad "1" smd circle
			(at -0.40005 0 180)
			(size 0 0)
			(layers "F.Cu" "F.Mask" "F.Paste")
			(net "P3V3_OCP_SFF")
		)
		(pad "2" smd circle
			(at 0.40005 0 180)
			(size 0 0)
			(layers "F.Cu" "F.Mask" "F.Paste")
			(net "SMB_OCP_SFF_3V3AUX_BUF_SCL")
		)
	)
)
